(kicad_pcb
	(version 20260206)
	(generator "pcbnew")
	(generator_version "10.0")
	(general
		(thickness 1.6)
		(legacy_teardrops no)
	)
	(paper "A4")
	(title_block
		(title "04192023_DAF0TMB3IC0_F0TG_MB_C_brd_V02_OCP.brd")
		(comment 1 "Grand Teton / footprints 6340-6346 of 8354")
	)
	(layers
		(0 "F.Cu" signal "TOP")
		(4 "In1.Cu" signal "GND")
		(6 "In2.Cu" signal "IN1")
		(8 "In3.Cu" signal "GND1")
		(10 "In4.Cu" signal "IN2")
		(12 "In5.Cu" signal "GND2")
		(14 "In6.Cu" signal "IN3")
		(16 "In7.Cu" signal "GND3")
		(18 "In8.Cu" signal "VCC")
		(20 "In9.Cu" signal "VCC1")
		(22 "In10.Cu" signal "GND4")
		(24 "In11.Cu" signal "IN4")
		(26 "In12.Cu" signal "GND5")
		(28 "In13.Cu" signal "IN5")
		(30 "In14.Cu" signal "GND6")
		(32 "In15.Cu" signal "IN6")
		(34 "In16.Cu" signal "GND7")
		(2 "B.Cu" signal "BOTTOM")
		(9 "F.Adhes" user "F.Adhesive")
		(11 "B.Adhes" user "B.Adhesive")
		(13 "F.Paste" user "Package Geometry/Pastemask Top")
		(15 "B.Paste" user "Package Geometry/Pastemask Bottom")
		(5 "F.SilkS" user "Ref Des/Silkscreen Top")
		(7 "B.SilkS" user "Ref Des/Silkscreen Bottom")
		(1 "F.Mask" user "Board Geometry/Soldermask Top")
		(3 "B.Mask" user "Board Geometry/Soldermask Bottom")
		(17 "Dwgs.User" user "User.Drawings")
		(19 "Cmts.User" user "User.Comments")
		(21 "Eco1.User" user "User.Eco1")
		(23 "Eco2.User" user "User.Eco2")
		(25 "Edge.Cuts" user "Board Geometry/Outline")
		(27 "Margin" user)
		(31 "F.CrtYd" user "Package Geometry/Place Bound Top")
		(29 "B.CrtYd" user "Package Geometry/Place Bound Bottom")
		(35 "F.Fab" user "Ref Des/Assembly Top")
		(33 "B.Fab" user "Ref Des/Assembly Bottom")
	)
	(footprint ""
		(layer "B.Cu")
		(at 316.590934 -398.942052 90)
		(property "Reference" "C572"
			(at 0 0 90)
			(layer "B.SilkS")
			(hide yes)
			(effects
				(font
					(size 1.27 1.27)
				)
				(justify mirror)
			)
		)
		(property "Value" ""
			(at 0 0 90)
			(layer "B.Fab")
			(effects
				(font
					(size 1.27 1.27)
				)
				(justify mirror)
			)
		)
		(duplicate_pad_numbers_are_jumpers no)
		(fp_line
			(start 0.7874 -0.4064)
			(end -0.7874 -0.4064)
			(stroke
				(width 0.1524)
				(type default)
			)
			(layer "B.SilkS")
		)
		(fp_line
			(start -0.7874 -0.4064)
			(end -0.7874 0.4064)
			(stroke
				(width 0.1524)
				(type default)
			)
			(layer "B.SilkS")
		)
		(fp_line
			(start 0.7874 0.4064)
			(end 0.7874 -0.4064)
			(stroke
				(width 0.1524)
				(type default)
			)
			(layer "B.SilkS")
		)
		(fp_line
			(start -0.7874 0.4064)
			(end 0.7874 0.4064)
			(stroke
				(width 0.1524)
				(type default)
			)
			(layer "B.SilkS")
		)
		(fp_line
			(start 0.67945 -0.305054)
			(end 0.12065 -0.305054)
			(stroke
				(width 0.1)
				(type default)
			)
			(layer "B.Fab")
		)
		(fp_line
			(start 0.12065 -0.305054)
			(end 0.12065 -0.2794)
			(stroke
				(width 0.1)
				(type default)
			)
			(layer "B.Fab")
		)
		(fp_line
			(start -0.12065 -0.3048)
			(end -0.67945 -0.3048)
			(stroke
				(width 0.1)
				(type default)
			)
			(layer "B.Fab")
		)
		(fp_line
			(start -0.67945 -0.3048)
			(end -0.67945 0.3048)
			(stroke
				(width 0.1)
				(type default)
			)
			(layer "B.Fab")
		)
		(fp_line
			(start 0.12065 -0.2794)
			(end -0.12065 -0.2794)
			(stroke
				(width 0.1)
				(type default)
			)
			(layer "B.Fab")
		)
		(fp_line
			(start -0.12065 -0.2794)
			(end -0.12065 -0.3048)
			(stroke
				(width 0.1)
				(type default)
			)
			(layer "B.Fab")
		)
		(fp_line
			(start 0.12065 0.2794)
			(end 0.12065 0.3048)
			(stroke
				(width 0.1)
				(type default)
			)
			(layer "B.Fab")
		)
		(fp_line
			(start -0.120396 0.2794)
			(end 0.12065 0.2794)
			(stroke
				(width 0.1)
				(type default)
			)
			(layer "B.Fab")
		)
		(fp_line
			(start 0.67945 0.3048)
			(end 0.67945 -0.305054)
			(stroke
				(width 0.1)
				(type default)
			)
			(layer "B.Fab")
		)
		(fp_line
			(start 0.12065 0.3048)
			(end 0.67945 0.3048)
			(stroke
				(width 0.1)
				(type default)
			)
			(layer "B.Fab")
		)
		(fp_line
			(start -0.120396 0.3048)
			(end -0.120396 0.2794)
			(stroke
				(width 0.1)
				(type default)
			)
			(layer "B.Fab")
		)
		(fp_line
			(start -0.67945 0.3048)
			(end -0.120396 0.3048)
			(stroke
				(width 0.1)
				(type default)
			)
			(layer "B.Fab")
		)
		(pad "1" smd circle
			(at 0.40005 0 270)
			(size 0 0)
			(layers "B.Cu" "B.Mask" "B.Paste")
			(net "P0V9_CPU0_RT0_2A")
		)
		(pad "2" smd circle
			(at -0.40005 0 270)
			(size 0 0)
			(layers "B.Cu" "B.Mask" "B.Paste")
			(net "GND")
		)
	)
	(footprint ""
		(layer "B.Cu")
		(at 233.172 -341.884 180)
		(property "Reference" "R977"
			(at 0 0 0)
			(layer "B.SilkS")
			(hide yes)
			(effects
				(font
					(size 1.27 1.27)
				)
				(justify mirror)
			)
		)
		(property "Value" ""
			(at 0 0 0)
			(layer "B.Fab")
			(effects
				(font
					(size 1.27 1.27)
				)
				(justify mirror)
			)
		)
		(duplicate_pad_numbers_are_jumpers no)
		(fp_line
			(start 0.32512 0.175006)
			(end 0.32512 -0.175006)
			(stroke
				(width 0.1)
				(type default)
			)
			(layer "B.Fab")
		)
		(fp_line
			(start 0.32512 -0.175006)
			(end -0.32512 -0.175006)
			(stroke
				(width 0.1)
				(type default)
			)
			(layer "B.Fab")
		)
		(fp_line
			(start -0.32512 0.175006)
			(end 0.32512 0.175006)
			(stroke
				(width 0.1)
				(type default)
			)
			(layer "B.Fab")
		)
		(fp_line
			(start -0.32512 -0.175006)
			(end -0.32512 0.175006)
			(stroke
				(width 0.1)
				(type default)
			)
			(layer "B.Fab")
		)
		(pad "1" smd rect
			(at 0.2667 0)
			(size 0.3048 0.381)
			(layers "B.Cu" "B.Mask" "B.Paste")
			(net "SMB_RT_CPU0_P0_R_SDA")
		)
		(pad "2" smd rect
			(at -0.2667 0 180)
			(size 0.3048 0.381)
			(layers "B.Cu" "B.Mask" "B.Paste")
			(net "SMB_RT_CPU0_P0_R2_SDA")
		)
	)
	(footprint ""
		(layer "B.Cu")
		(at 155.419044 -390.560052 90)
		(property "Reference" "C371"
			(at 0 0 90)
			(layer "B.SilkS")
			(hide yes)
			(effects
				(font
					(size 1.27 1.27)
				)
				(justify mirror)
			)
		)
		(property "Value" ""
			(at 0 0 90)
			(layer "B.Fab")
			(effects
				(font
					(size 1.27 1.27)
				)
				(justify mirror)
			)
		)
		(duplicate_pad_numbers_are_jumpers no)
		(fp_line
			(start 0.7874 -0.4064)
			(end -0.7874 -0.4064)
			(stroke
				(width 0.1524)
				(type default)
			)
			(layer "B.SilkS")
		)
		(fp_line
			(start -0.7874 -0.4064)
			(end -0.7874 0.4064)
			(stroke
				(width 0.1524)
				(type default)
			)
			(layer "B.SilkS")
		)
		(fp_line
			(start 0.7874 0.4064)
			(end 0.7874 -0.4064)
			(stroke
				(width 0.1524)
				(type default)
			)
			(layer "B.SilkS")
		)
		(fp_line
			(start -0.7874 0.4064)
			(end 0.7874 0.4064)
			(stroke
				(width 0.1524)
				(type default)
			)
			(layer "B.SilkS")
		)
		(fp_line
			(start 0.67945 -0.305054)
			(end 0.12065 -0.305054)
			(stroke
				(width 0.1)
				(type default)
			)
			(layer "B.Fab")
		)
		(fp_line
			(start 0.12065 -0.305054)
			(end 0.12065 -0.2794)
			(stroke
				(width 0.1)
				(type default)
			)
			(layer "B.Fab")
		)
		(fp_line
			(start -0.12065 -0.3048)
			(end -0.67945 -0.3048)
			(stroke
				(width 0.1)
				(type default)
			)
			(layer "B.Fab")
		)
		(fp_line
			(start -0.67945 -0.3048)
			(end -0.67945 0.3048)
			(stroke
				(width 0.1)
				(type default)
			)
			(layer "B.Fab")
		)
		(fp_line
			(start 0.12065 -0.2794)
			(end -0.12065 -0.2794)
			(stroke
				(width 0.1)
				(type default)
			)
			(layer "B.Fab")
		)
		(fp_line
			(start -0.12065 -0.2794)
			(end -0.12065 -0.3048)
			(stroke
				(width 0.1)
				(type default)
			)
			(layer "B.Fab")
		)
		(fp_line
			(start 0.12065 0.2794)
			(end 0.12065 0.3048)
			(stroke
				(width 0.1)
				(type default)
			)
			(layer "B.Fab")
		)
		(fp_line
			(start -0.120396 0.2794)
			(end 0.12065 0.2794)
			(stroke
				(width 0.1)
				(type default)
			)
			(layer "B.Fab")
		)
		(fp_line
			(start 0.67945 0.3048)
			(end 0.67945 -0.305054)
			(stroke
				(width 0.1)
				(type default)
			)
			(layer "B.Fab")
		)
		(fp_line
			(start 0.12065 0.3048)
			(end 0.67945 0.3048)
			(stroke
				(width 0.1)
				(type default)
			)
			(layer "B.Fab")
		)
		(fp_line
			(start -0.120396 0.3048)
			(end -0.120396 0.2794)
			(stroke
				(width 0.1)
				(type default)
			)
			(layer "B.Fab")
		)
		(fp_line
			(start -0.67945 0.3048)
			(end -0.120396 0.3048)
			(stroke
				(width 0.1)
				(type default)
			)
			(layer "B.Fab")
		)
		(pad "1" smd circle
			(at 0.40005 0 270)
			(size 0 0)
			(layers "B.Cu" "B.Mask" "B.Paste")
			(net "P1V8_CPU1_RT2_1A")
		)
		(pad "2" smd circle
			(at -0.40005 0 270)
			(size 0 0)
			(layers "B.Cu" "B.Mask" "B.Paste")
			(net "GND")
		)
	)
	(footprint ""
		(layer "B.Cu")
		(at 101.385878 -142.59941 180)
		(property "Reference" "PC243"
			(at 0 0 0)
			(layer "B.SilkS")
			(hide yes)
			(effects
				(font
					(size 1.27 1.27)
				)
				(justify mirror)
			)
		)
		(property "Value" ""
			(at 0 0 0)
			(layer "B.Fab")
			(effects
				(font
					(size 1.27 1.27)
				)
				(justify mirror)
			)
		)
		(duplicate_pad_numbers_are_jumpers no)
		(fp_line
			(start 0.7874 0.4064)
			(end 0.7874 -0.4064)
			(stroke
				(width 0.1524)
				(type default)
			)
			(layer "B.SilkS")
		)
		(fp_line
			(start 0.7874 -0.4064)
			(end -0.7874 -0.4064)
			(stroke
				(width 0.1524)
				(type default)
			)
			(layer "B.SilkS")
		)
		(fp_line
			(start -0.7874 0.4064)
			(end 0.7874 0.4064)
			(stroke
				(width 0.1524)
				(type default)
			)
			(layer "B.SilkS")
		)
		(fp_line
			(start -0.7874 -0.4064)
			(end -0.7874 0.4064)
			(stroke
				(width 0.1524)
				(type default)
			)
			(layer "B.SilkS")
		)
		(fp_line
			(start 0.67945 0.3048)
			(end 0.67945 -0.305054)
			(stroke
				(width 0.1)
				(type default)
			)
			(layer "B.Fab")
		)
		(fp_line
			(start 0.67945 -0.305054)
			(end 0.12065 -0.305054)
			(stroke
				(width 0.1)
				(type default)
			)
			(layer "B.Fab")
		)
		(fp_line
			(start 0.12065 0.3048)
			(end 0.67945 0.3048)
			(stroke
				(width 0.1)
				(type default)
			)
			(layer "B.Fab")
		)
		(fp_line
			(start 0.12065 0.2794)
			(end 0.12065 0.3048)
			(stroke
				(width 0.1)
				(type default)
			)
			(layer "B.Fab")
		)
		(fp_line
			(start 0.12065 -0.2794)
			(end -0.12065 -0.2794)
			(stroke
				(width 0.1)
				(type default)
			)
			(layer "B.Fab")
		)
		(fp_line
			(start 0.12065 -0.305054)
			(end 0.12065 -0.2794)
			(stroke
				(width 0.1)
				(type default)
			)
			(layer "B.Fab")
		)
		(fp_line
			(start -0.120396 0.3048)
			(end -0.120396 0.2794)
			(stroke
				(width 0.1)
				(type default)
			)
			(layer "B.Fab")
		)
		(fp_line
			(start -0.120396 0.2794)
			(end 0.12065 0.2794)
			(stroke
				(width 0.1)
				(type default)
			)
			(layer "B.Fab")
		)
		(fp_line
			(start -0.12065 -0.2794)
			(end -0.12065 -0.3048)
			(stroke
				(width 0.1)
				(type default)
			)
			(layer "B.Fab")
		)
		(fp_line
			(start -0.12065 -0.3048)
			(end -0.67945 -0.3048)
			(stroke
				(width 0.1)
				(type default)
			)
			(layer "B.Fab")
		)
		(fp_line
			(start -0.67945 0.3048)
			(end -0.120396 0.3048)
			(stroke
				(width 0.1)
				(type default)
			)
			(layer "B.Fab")
		)
		(fp_line
			(start -0.67945 -0.3048)
			(end -0.67945 0.3048)
			(stroke
				(width 0.1)
				(type default)
			)
			(layer "B.Fab")
		)
		(pad "1" smd circle
			(at 0.40005 0)
			(size 0 0)
			(layers "B.Cu" "B.Mask" "B.Paste")
			(net "PVDDCR_CPU0_P1_VMON")
		)
		(pad "2" smd circle
			(at -0.40005 0)
			(size 0 0)
			(layers "B.Cu" "B.Mask" "B.Paste")
			(net "GND")
		)
	)
	(footprint ""
		(layer "B.Cu")
		(at 265.54811 -192.660016 180)
		(property "Reference" "C155"
			(at 0 0 0)
			(layer "B.SilkS")
			(hide yes)
			(effects
				(font
					(size 1.27 1.27)
				)
				(justify mirror)
			)
		)
		(property "Value" ""
			(at 0 0 0)
			(layer "B.Fab")
			(effects
				(font
					(size 1.27 1.27)
				)
				(justify mirror)
			)
		)
		(duplicate_pad_numbers_are_jumpers no)
		(fp_line
			(start 1.524 0.762)
			(end 1.524 -0.762)
			(stroke
				(width 0.1524)
				(type default)
			)
			(layer "B.SilkS")
		)
		(fp_line
			(start 1.524 -0.762)
			(end -1.524 -0.762)
			(stroke
				(width 0.1524)
				(type default)
			)
			(layer "B.SilkS")
		)
		(fp_line
			(start -1.524 0.762)
			(end 1.524 0.762)
			(stroke
				(width 0.1524)
				(type default)
			)
			(layer "B.SilkS")
		)
		(fp_line
			(start -1.524 -0.762)
			(end -1.524 0.762)
			(stroke
				(width 0.1524)
				(type default)
			)
			(layer "B.SilkS")
		)
		(fp_line
			(start 1.1049 0.724916)
			(end -1.1049 0.724916)
			(stroke
				(width 0.1)
				(type default)
			)
			(layer "B.Fab")
		)
		(fp_line
			(start 1.1049 -0.724916)
			(end 1.1049 0.724916)
			(stroke
				(width 0.1)
				(type default)
			)
			(layer "B.Fab")
		)
		(fp_line
			(start -1.1049 0.724916)
			(end -1.1049 -0.724916)
			(stroke
				(width 0.1)
				(type default)
			)
			(layer "B.Fab")
		)
		(fp_line
			(start -1.1049 -0.724916)
			(end 1.1049 -0.724916)
			(stroke
				(width 0.1)
				(type default)
			)
			(layer "B.Fab")
		)
		(pad "1" smd rect
			(at 0.889 0 180)
			(size 1.016 1.27)
			(layers "B.Cu" "B.Mask" "B.Paste")
			(net "P12V_MEM_CPU0")
		)
		(pad "2" smd rect
			(at -0.889 0 180)
			(size 1.016 1.27)
			(layers "B.Cu" "B.Mask" "B.Paste")
			(net "GND")
		)
	)
	(footprint ""
		(layer "B.Cu")
		(at 148.218906 -390.560052 90)
		(property "Reference" "C417"
			(at 0 0 90)
			(layer "B.SilkS")
			(hide yes)
			(effects
				(font
					(size 1.27 1.27)
				)
				(justify mirror)
			)
		)
		(property "Value" ""
			(at 0 0 90)
			(layer "B.Fab")
			(effects
				(font
					(size 1.27 1.27)
				)
				(justify mirror)
			)
		)
		(duplicate_pad_numbers_are_jumpers no)
		(fp_line
			(start 0.7874 -0.4064)
			(end -0.7874 -0.4064)
			(stroke
				(width 0.1524)
				(type default)
			)
			(layer "B.SilkS")
		)
		(fp_line
			(start -0.7874 -0.4064)
			(end -0.7874 0.4064)
			(stroke
				(width 0.1524)
				(type default)
			)
			(layer "B.SilkS")
		)
		(fp_line
			(start 0.7874 0.4064)
			(end 0.7874 -0.4064)
			(stroke
				(width 0.1524)
				(type default)
			)
			(layer "B.SilkS")
		)
		(fp_line
			(start -0.7874 0.4064)
			(end 0.7874 0.4064)
			(stroke
				(width 0.1524)
				(type default)
			)
			(layer "B.SilkS")
		)
		(fp_line
			(start 0.67945 -0.305054)
			(end 0.12065 -0.305054)
			(stroke
				(width 0.1)
				(type default)
			)
			(layer "B.Fab")
		)
		(fp_line
			(start 0.12065 -0.305054)
			(end 0.12065 -0.2794)
			(stroke
				(width 0.1)
				(type default)
			)
			(layer "B.Fab")
		)
		(fp_line
			(start -0.12065 -0.3048)
			(end -0.67945 -0.3048)
			(stroke
				(width 0.1)
				(type default)
			)
			(layer "B.Fab")
		)
		(fp_line
			(start -0.67945 -0.3048)
			(end -0.67945 0.3048)
			(stroke
				(width 0.1)
				(type default)
			)
			(layer "B.Fab")
		)
		(fp_line
			(start 0.12065 -0.2794)
			(end -0.12065 -0.2794)
			(stroke
				(width 0.1)
				(type default)
			)
			(layer "B.Fab")
		)
		(fp_line
			(start -0.12065 -0.2794)
			(end -0.12065 -0.3048)
			(stroke
				(width 0.1)
				(type default)
			)
			(layer "B.Fab")
		)
		(fp_line
			(start 0.12065 0.2794)
			(end 0.12065 0.3048)
			(stroke
				(width 0.1)
				(type default)
			)
			(layer "B.Fab")
		)
		(fp_line
			(start -0.120396 0.2794)
			(end 0.12065 0.2794)
			(stroke
				(width 0.1)
				(type default)
			)
			(layer "B.Fab")
		)
		(fp_line
			(start 0.67945 0.3048)
			(end 0.67945 -0.305054)
			(stroke
				(width 0.1)
				(type default)
			)
			(layer "B.Fab")
		)
		(fp_line
			(start 0.12065 0.3048)
			(end 0.67945 0.3048)
			(stroke
				(width 0.1)
				(type default)
			)
			(layer "B.Fab")
		)
		(fp_line
			(start -0.120396 0.3048)
			(end -0.120396 0.2794)
			(stroke
				(width 0.1)
				(type default)
			)
			(layer "B.Fab")
		)
		(fp_line
			(start -0.67945 0.3048)
			(end -0.120396 0.3048)
			(stroke
				(width 0.1)
				(type default)
			)
			(layer "B.Fab")
		)
		(pad "1" smd circle
			(at 0.40005 0 270)
			(size 0 0)
			(layers "B.Cu" "B.Mask" "B.Paste")
			(net "P0V9_CPU1_RT2_2A")
		)
		(pad "2" smd circle
			(at -0.40005 0 270)
			(size 0 0)
			(layers "B.Cu" "B.Mask" "B.Paste")
			(net "GND")
		)
	)
	(footprint ""
		(layer "B.Cu")
		(at 112.35436 -408.651456 90)
		(property "Reference" "R696"
			(at 0 0 90)
			(layer "B.SilkS")
			(hide yes)
			(effects
				(font
					(size 1.27 1.27)
				)
				(justify mirror)
			)
		)
		(property "Value" ""
			(at 0 0 90)
			(layer "B.Fab")
			(effects
				(font
					(size 1.27 1.27)
				)
				(justify mirror)
			)
		)
		(duplicate_pad_numbers_are_jumpers no)
		(fp_line
			(start 0.32512 -0.175006)
			(end -0.32512 -0.175006)
			(stroke
				(width 0.1)
				(type default)
			)
			(layer "B.Fab")
		)
		(fp_line
			(start -0.32512 -0.175006)
			(end -0.32512 0.175006)
			(stroke
				(width 0.1)
				(type default)
			)
			(layer "B.Fab")
		)
		(fp_line
			(start 0.32512 0.175006)
			(end 0.32512 -0.175006)
			(stroke
				(width 0.1)
				(type default)
			)
			(layer "B.Fab")
		)
		(fp_line
			(start -0.32512 0.175006)
			(end 0.32512 0.175006)
			(stroke
				(width 0.1)
				(type default)
			)
			(layer "B.Fab")
		)
		(pad "1" smd rect
			(at 0.2667 0 270)
			(size 0.3048 0.381)
			(layers "B.Cu" "B.Mask" "B.Paste")
			(net "SMB_RT_CPU1_P3_ROM_MUX_1D_SDA")
		)
		(pad "2" smd rect
			(at -0.2667 0 90)
			(size 0.3048 0.381)
			(layers "B.Cu" "B.Mask" "B.Paste")
			(net "SMB_RT_CPU1_P3_ROM_MUX_1D_R_SDA")
		)
	)
)
